(kicad_pcb
	(version 20260206)
	(generator "pcbnew")
	(generator_version "10.0")
	(general
		(thickness 1.6)
		(legacy_teardrops no)
	)
	(paper "A4")
	(title_block
		(title "04192023_DAF0TMB3IC0_F0TG_MB_C_brd_V02_OCP.brd")
		(comment 1 "Grand Teton / footprints 6193-6198 of 8354")
	)
	(layers
		(0 "F.Cu" signal "TOP")
		(4 "In1.Cu" signal "GND")
		(6 "In2.Cu" signal "IN1")
		(8 "In3.Cu" signal "GND1")
		(10 "In4.Cu" signal "IN2")
		(12 "In5.Cu" signal "GND2")
		(14 "In6.Cu" signal "IN3")
		(16 "In7.Cu" signal "GND3")
		(18 "In8.Cu" signal "VCC")
		(20 "In9.Cu" signal "VCC1")
		(22 "In10.Cu" signal "GND4")
		(24 "In11.Cu" signal "IN4")
		(26 "In12.Cu" signal "GND5")
		(28 "In13.Cu" signal "IN5")
		(30 "In14.Cu" signal "GND6")
		(32 "In15.Cu" signal "IN6")
		(34 "In16.Cu" signal "GND7")
		(2 "B.Cu" signal "BOTTOM")
		(9 "F.Adhes" user "F.Adhesive")
		(11 "B.Adhes" user "B.Adhesive")
		(13 "F.Paste" user "Package Geometry/Pastemask Top")
		(15 "B.Paste" user "Package Geometry/Pastemask Bottom")
		(5 "F.SilkS" user "Ref Des/Silkscreen Top")
		(7 "B.SilkS" user "Ref Des/Silkscreen Bottom")
		(1 "F.Mask" user "Board Geometry/Soldermask Top")
		(3 "B.Mask" user "Board Geometry/Soldermask Bottom")
		(17 "Dwgs.User" user "User.Drawings")
		(19 "Cmts.User" user "User.Comments")
		(21 "Eco1.User" user "User.Eco1")
		(23 "Eco2.User" user "User.Eco2")
		(25 "Edge.Cuts" user "Board Geometry/Outline")
		(27 "Margin" user)
		(31 "F.CrtYd" user "Package Geometry/Place Bound Top")
		(29 "B.CrtYd" user "Package Geometry/Place Bound Bottom")
		(35 "F.Fab" user "Ref Des/Assembly Top")
		(33 "B.Fab" user "Ref Des/Assembly Bottom")
	)
	(footprint ""
		(layer "B.Cu")
		(at 357.730806 -419.02888 180)
		(property "Reference" "R2837"
			(at 0 0 0)
			(layer "B.SilkS")
			(hide yes)
			(effects
				(font
					(size 1.27 1.27)
				)
				(justify mirror)
			)
		)
		(property "Value" ""
			(at 0 0 0)
			(layer "B.Fab")
			(effects
				(font
					(size 1.27 1.27)
				)
				(justify mirror)
			)
		)
		(duplicate_pad_numbers_are_jumpers no)
		(fp_line
			(start 0.7874 0.4064)
			(end 0.7874 -0.4064)
			(stroke
				(width 0.1524)
				(type default)
			)
			(layer "B.SilkS")
		)
		(fp_line
			(start 0.7874 -0.4064)
			(end -0.7874 -0.4064)
			(stroke
				(width 0.1524)
				(type default)
			)
			(layer "B.SilkS")
		)
		(fp_line
			(start -0.7874 0.4064)
			(end 0.7874 0.4064)
			(stroke
				(width 0.1524)
				(type default)
			)
			(layer "B.SilkS")
		)
		(fp_line
			(start -0.7874 -0.4064)
			(end -0.7874 0.4064)
			(stroke
				(width 0.1524)
				(type default)
			)
			(layer "B.SilkS")
		)
		(fp_line
			(start 0.67945 0.3048)
			(end 0.67945 -0.305054)
			(stroke
				(width 0.1)
				(type default)
			)
			(layer "B.Fab")
		)
		(fp_line
			(start 0.67945 -0.305054)
			(end 0.12065 -0.305054)
			(stroke
				(width 0.1)
				(type default)
			)
			(layer "B.Fab")
		)
		(fp_line
			(start 0.12065 0.3048)
			(end 0.67945 0.3048)
			(stroke
				(width 0.1)
				(type default)
			)
			(layer "B.Fab")
		)
		(fp_line
			(start 0.12065 0.2794)
			(end 0.12065 0.3048)
			(stroke
				(width 0.1)
				(type default)
			)
			(layer "B.Fab")
		)
		(fp_line
			(start 0.12065 -0.2794)
			(end -0.12065 -0.2794)
			(stroke
				(width 0.1)
				(type default)
			)
			(layer "B.Fab")
		)
		(fp_line
			(start 0.12065 -0.305054)
			(end 0.12065 -0.2794)
			(stroke
				(width 0.1)
				(type default)
			)
			(layer "B.Fab")
		)
		(fp_line
			(start -0.120396 0.3048)
			(end -0.120396 0.2794)
			(stroke
				(width 0.1)
				(type default)
			)
			(layer "B.Fab")
		)
		(fp_line
			(start -0.120396 0.2794)
			(end 0.12065 0.2794)
			(stroke
				(width 0.1)
				(type default)
			)
			(layer "B.Fab")
		)
		(fp_line
			(start -0.12065 -0.2794)
			(end -0.12065 -0.3048)
			(stroke
				(width 0.1)
				(type default)
			)
			(layer "B.Fab")
		)
		(fp_line
			(start -0.12065 -0.3048)
			(end -0.67945 -0.3048)
			(stroke
				(width 0.1)
				(type default)
			)
			(layer "B.Fab")
		)
		(fp_line
			(start -0.67945 0.3048)
			(end -0.120396 0.3048)
			(stroke
				(width 0.1)
				(type default)
			)
			(layer "B.Fab")
		)
		(fp_line
			(start -0.67945 -0.3048)
			(end -0.67945 0.3048)
			(stroke
				(width 0.1)
				(type default)
			)
			(layer "B.Fab")
		)
		(pad "1" smd circle
			(at 0.40005 0)
			(size 0 0)
			(layers "B.Cu" "B.Mask" "B.Paste")
			(net "P3V3_AUX")
		)
		(pad "2" smd circle
			(at -0.40005 0)
			(size 0 0)
			(layers "B.Cu" "B.Mask" "B.Paste")
			(net "FM_SWB_PWRGD")
		)
	)
	(footprint ""
		(layer "B.Cu")
		(at 136.936226 -391.81405 180)
		(property "Reference" "C471"
			(at 0 0 0)
			(layer "B.SilkS")
			(hide yes)
			(effects
				(font
					(size 1.27 1.27)
				)
				(justify mirror)
			)
		)
		(property "Value" ""
			(at 0 0 0)
			(layer "B.Fab")
			(effects
				(font
					(size 1.27 1.27)
				)
				(justify mirror)
			)
		)
		(duplicate_pad_numbers_are_jumpers no)
		(fp_line
			(start 1.524 0.762)
			(end 1.524 -0.762)
			(stroke
				(width 0.1524)
				(type default)
			)
			(layer "B.SilkS")
		)
		(fp_line
			(start 1.524 -0.762)
			(end -1.524 -0.762)
			(stroke
				(width 0.1524)
				(type default)
			)
			(layer "B.SilkS")
		)
		(fp_line
			(start -1.524 0.762)
			(end 1.524 0.762)
			(stroke
				(width 0.1524)
				(type default)
			)
			(layer "B.SilkS")
		)
		(fp_line
			(start -1.524 -0.762)
			(end -1.524 0.762)
			(stroke
				(width 0.1524)
				(type default)
			)
			(layer "B.SilkS")
		)
		(fp_line
			(start 1.1049 0.724916)
			(end -1.1049 0.724916)
			(stroke
				(width 0.1)
				(type default)
			)
			(layer "B.Fab")
		)
		(fp_line
			(start 1.1049 -0.724916)
			(end 1.1049 0.724916)
			(stroke
				(width 0.1)
				(type default)
			)
			(layer "B.Fab")
		)
		(fp_line
			(start -1.1049 0.724916)
			(end -1.1049 -0.724916)
			(stroke
				(width 0.1)
				(type default)
			)
			(layer "B.Fab")
		)
		(fp_line
			(start -1.1049 -0.724916)
			(end 1.1049 -0.724916)
			(stroke
				(width 0.1)
				(type default)
			)
			(layer "B.Fab")
		)
		(pad "1" smd rect
			(at 0.889 0 180)
			(size 1.016 1.27)
			(layers "B.Cu" "B.Mask" "B.Paste")
			(net "P0V9_CPU1_RT3_2A")
		)
		(pad "2" smd rect
			(at -0.889 0 180)
			(size 1.016 1.27)
			(layers "B.Cu" "B.Mask" "B.Paste")
			(net "GND")
		)
	)
	(footprint ""
		(layer "B.Cu")
		(at 179.258468 -353.960684 -90)
		(property "Reference" "PR332"
			(at 0 0 90)
			(layer "B.SilkS")
			(hide yes)
			(effects
				(font
					(size 1.27 1.27)
				)
				(justify mirror)
			)
		)
		(property "Value" ""
			(at 0 0 90)
			(layer "B.Fab")
			(effects
				(font
					(size 1.27 1.27)
				)
				(justify mirror)
			)
		)
		(duplicate_pad_numbers_are_jumpers no)
		(fp_line
			(start -0.7874 0.4064)
			(end 0.7874 0.4064)
			(stroke
				(width 0.1524)
				(type default)
			)
			(layer "B.SilkS")
		)
		(fp_line
			(start 0.7874 0.4064)
			(end 0.7874 -0.4064)
			(stroke
				(width 0.1524)
				(type default)
			)
			(layer "B.SilkS")
		)
		(fp_line
			(start -0.7874 -0.4064)
			(end -0.7874 0.4064)
			(stroke
				(width 0.1524)
				(type default)
			)
			(layer "B.SilkS")
		)
		(fp_line
			(start 0.7874 -0.4064)
			(end -0.7874 -0.4064)
			(stroke
				(width 0.1524)
				(type default)
			)
			(layer "B.SilkS")
		)
		(fp_line
			(start -0.67945 0.3048)
			(end -0.120396 0.3048)
			(stroke
				(width 0.1)
				(type default)
			)
			(layer "B.Fab")
		)
		(fp_line
			(start -0.120396 0.3048)
			(end -0.120396 0.2794)
			(stroke
				(width 0.1)
				(type default)
			)
			(layer "B.Fab")
		)
		(fp_line
			(start 0.12065 0.3048)
			(end 0.67945 0.3048)
			(stroke
				(width 0.1)
				(type default)
			)
			(layer "B.Fab")
		)
		(fp_line
			(start 0.67945 0.3048)
			(end 0.67945 -0.305054)
			(stroke
				(width 0.1)
				(type default)
			)
			(layer "B.Fab")
		)
		(fp_line
			(start -0.120396 0.2794)
			(end 0.12065 0.2794)
			(stroke
				(width 0.1)
				(type default)
			)
			(layer "B.Fab")
		)
		(fp_line
			(start 0.12065 0.2794)
			(end 0.12065 0.3048)
			(stroke
				(width 0.1)
				(type default)
			)
			(layer "B.Fab")
		)
		(fp_line
			(start -0.12065 -0.2794)
			(end -0.12065 -0.3048)
			(stroke
				(width 0.1)
				(type default)
			)
			(layer "B.Fab")
		)
		(fp_line
			(start 0.12065 -0.2794)
			(end -0.12065 -0.2794)
			(stroke
				(width 0.1)
				(type default)
			)
			(layer "B.Fab")
		)
		(fp_line
			(start -0.67945 -0.3048)
			(end -0.67945 0.3048)
			(stroke
				(width 0.1)
				(type default)
			)
			(layer "B.Fab")
		)
		(fp_line
			(start -0.12065 -0.3048)
			(end -0.67945 -0.3048)
			(stroke
				(width 0.1)
				(type default)
			)
			(layer "B.Fab")
		)
		(fp_line
			(start 0.12065 -0.305054)
			(end 0.12065 -0.2794)
			(stroke
				(width 0.1)
				(type default)
			)
			(layer "B.Fab")
		)
		(fp_line
			(start 0.67945 -0.305054)
			(end 0.12065 -0.305054)
			(stroke
				(width 0.1)
				(type default)
			)
			(layer "B.Fab")
		)
		(pad "1" smd circle
			(at 0.40005 0 90)
			(size 0 0)
			(layers "B.Cu" "B.Mask" "B.Paste")
			(net "PVDD11_S3_P1_VOS1")
		)
		(pad "2" smd circle
			(at -0.40005 0 90)
			(size 0 0)
			(layers "B.Cu" "B.Mask" "B.Paste")
			(net "PVDD11_S3_P1")
		)
	)
	(footprint ""
		(layer "B.Cu")
		(at 445.888364 -195.86067 180)
		(property "Reference" "R1685"
			(at 0 0 0)
			(layer "B.SilkS")
			(hide yes)
			(effects
				(font
					(size 1.27 1.27)
				)
				(justify mirror)
			)
		)
		(property "Value" ""
			(at 0 0 0)
			(layer "B.Fab")
			(effects
				(font
					(size 1.27 1.27)
				)
				(justify mirror)
			)
		)
		(duplicate_pad_numbers_are_jumpers no)
		(fp_line
			(start 0.7874 0.4064)
			(end 0.7874 -0.4064)
			(stroke
				(width 0.1524)
				(type default)
			)
			(layer "B.SilkS")
		)
		(fp_line
			(start 0.7874 -0.4064)
			(end -0.7874 -0.4064)
			(stroke
				(width 0.1524)
				(type default)
			)
			(layer "B.SilkS")
		)
		(fp_line
			(start -0.7874 0.4064)
			(end 0.7874 0.4064)
			(stroke
				(width 0.1524)
				(type default)
			)
			(layer "B.SilkS")
		)
		(fp_line
			(start -0.7874 -0.4064)
			(end -0.7874 0.4064)
			(stroke
				(width 0.1524)
				(type default)
			)
			(layer "B.SilkS")
		)
		(fp_line
			(start 0.67945 0.3048)
			(end 0.67945 -0.305054)
			(stroke
				(width 0.1)
				(type default)
			)
			(layer "B.Fab")
		)
		(fp_line
			(start 0.67945 -0.305054)
			(end 0.12065 -0.305054)
			(stroke
				(width 0.1)
				(type default)
			)
			(layer "B.Fab")
		)
		(fp_line
			(start 0.12065 0.3048)
			(end 0.67945 0.3048)
			(stroke
				(width 0.1)
				(type default)
			)
			(layer "B.Fab")
		)
		(fp_line
			(start 0.12065 0.2794)
			(end 0.12065 0.3048)
			(stroke
				(width 0.1)
				(type default)
			)
			(layer "B.Fab")
		)
		(fp_line
			(start 0.12065 -0.2794)
			(end -0.12065 -0.2794)
			(stroke
				(width 0.1)
				(type default)
			)
			(layer "B.Fab")
		)
		(fp_line
			(start 0.12065 -0.305054)
			(end 0.12065 -0.2794)
			(stroke
				(width 0.1)
				(type default)
			)
			(layer "B.Fab")
		)
		(fp_line
			(start -0.120396 0.3048)
			(end -0.120396 0.2794)
			(stroke
				(width 0.1)
				(type default)
			)
			(layer "B.Fab")
		)
		(fp_line
			(start -0.120396 0.2794)
			(end 0.12065 0.2794)
			(stroke
				(width 0.1)
				(type default)
			)
			(layer "B.Fab")
		)
		(fp_line
			(start -0.12065 -0.2794)
			(end -0.12065 -0.3048)
			(stroke
				(width 0.1)
				(type default)
			)
			(layer "B.Fab")
		)
		(fp_line
			(start -0.12065 -0.3048)
			(end -0.67945 -0.3048)
			(stroke
				(width 0.1)
				(type default)
			)
			(layer "B.Fab")
		)
		(fp_line
			(start -0.67945 0.3048)
			(end -0.120396 0.3048)
			(stroke
				(width 0.1)
				(type default)
			)
			(layer "B.Fab")
		)
		(fp_line
			(start -0.67945 -0.3048)
			(end -0.67945 0.3048)
			(stroke
				(width 0.1)
				(type default)
			)
			(layer "B.Fab")
		)
		(pad "1" smd circle
			(at 0.40005 0)
			(size 0 0)
			(layers "B.Cu" "B.Mask" "B.Paste")
			(net "I3C_SPD_DDRGL_CPU0_SDA")
		)
		(pad "2" smd circle
			(at -0.40005 0)
			(size 0 0)
			(layers "B.Cu" "B.Mask" "B.Paste")
			(net "I3C_SPD_DDRK_CPU0_SDA")
		)
	)
	(footprint ""
		(layer "B.Cu")
		(at 325.799958 -202.113896 90)
		(property "Reference" "R413"
			(at 0 0 90)
			(layer "B.SilkS")
			(hide yes)
			(effects
				(font
					(size 1.27 1.27)
				)
				(justify mirror)
			)
		)
		(property "Value" ""
			(at 0 0 90)
			(layer "B.Fab")
			(effects
				(font
					(size 1.27 1.27)
				)
				(justify mirror)
			)
		)
		(duplicate_pad_numbers_are_jumpers no)
		(fp_line
			(start 0.7874 -0.4064)
			(end -0.7874 -0.4064)
			(stroke
				(width 0.1524)
				(type default)
			)
			(layer "B.SilkS")
		)
		(fp_line
			(start -0.7874 -0.4064)
			(end -0.7874 0.4064)
			(stroke
				(width 0.1524)
				(type default)
			)
			(layer "B.SilkS")
		)
		(fp_line
			(start 0.7874 0.4064)
			(end 0.7874 -0.4064)
			(stroke
				(width 0.1524)
				(type default)
			)
			(layer "B.SilkS")
		)
		(fp_line
			(start -0.7874 0.4064)
			(end 0.7874 0.4064)
			(stroke
				(width 0.1524)
				(type default)
			)
			(layer "B.SilkS")
		)
		(fp_line
			(start 0.67945 -0.305054)
			(end 0.12065 -0.305054)
			(stroke
				(width 0.1)
				(type default)
			)
			(layer "B.Fab")
		)
		(fp_line
			(start 0.12065 -0.305054)
			(end 0.12065 -0.2794)
			(stroke
				(width 0.1)
				(type default)
			)
			(layer "B.Fab")
		)
		(fp_line
			(start -0.12065 -0.3048)
			(end -0.67945 -0.3048)
			(stroke
				(width 0.1)
				(type default)
			)
			(layer "B.Fab")
		)
		(fp_line
			(start -0.67945 -0.3048)
			(end -0.67945 0.3048)
			(stroke
				(width 0.1)
				(type default)
			)
			(layer "B.Fab")
		)
		(fp_line
			(start 0.12065 -0.2794)
			(end -0.12065 -0.2794)
			(stroke
				(width 0.1)
				(type default)
			)
			(layer "B.Fab")
		)
		(fp_line
			(start -0.12065 -0.2794)
			(end -0.12065 -0.3048)
			(stroke
				(width 0.1)
				(type default)
			)
			(layer "B.Fab")
		)
		(fp_line
			(start 0.12065 0.2794)
			(end 0.12065 0.3048)
			(stroke
				(width 0.1)
				(type default)
			)
			(layer "B.Fab")
		)
		(fp_line
			(start -0.120396 0.2794)
			(end 0.12065 0.2794)
			(stroke
				(width 0.1)
				(type default)
			)
			(layer "B.Fab")
		)
		(fp_line
			(start 0.67945 0.3048)
			(end 0.67945 -0.305054)
			(stroke
				(width 0.1)
				(type default)
			)
			(layer "B.Fab")
		)
		(fp_line
			(start 0.12065 0.3048)
			(end 0.67945 0.3048)
			(stroke
				(width 0.1)
				(type default)
			)
			(layer "B.Fab")
		)
		(fp_line
			(start -0.120396 0.3048)
			(end -0.120396 0.2794)
			(stroke
				(width 0.1)
				(type default)
			)
			(layer "B.Fab")
		)
		(fp_line
			(start -0.67945 0.3048)
			(end -0.120396 0.3048)
			(stroke
				(width 0.1)
				(type default)
			)
			(layer "B.Fab")
		)
		(pad "1" smd circle
			(at 0.40005 0 270)
			(size 0 0)
			(layers "B.Cu" "B.Mask" "B.Paste")
			(net "CPU0_XTRIG_L4")
		)
		(pad "2" smd circle
			(at -0.40005 0 270)
			(size 0 0)
			(layers "B.Cu" "B.Mask" "B.Paste")
			(net "PVDD18_S5_P0")
		)
	)
	(footprint ""
		(layer "B.Cu")
		(at 439.029602 -423.66311)
		(property "Reference" "PR6810"
			(at 0 0 0)
			(layer "B.SilkS")
			(hide yes)
			(effects
				(font
					(size 1.27 1.27)
				)
				(justify mirror)
			)
		)
		(property "Value" ""
			(at 0 0 0)
			(layer "B.Fab")
			(effects
				(font
					(size 1.27 1.27)
				)
				(justify mirror)
			)
		)
		(duplicate_pad_numbers_are_jumpers no)
		(fp_line
			(start -0.7874 -0.4064)
			(end -0.7874 0.4064)
			(stroke
				(width 0.1524)
				(type default)
			)
			(layer "B.SilkS")
		)
		(fp_line
			(start -0.7874 0.4064)
			(end 0.7874 0.4064)
			(stroke
				(width 0.1524)
				(type default)
			)
			(layer "B.SilkS")
		)
		(fp_line
			(start 0.7874 -0.4064)
			(end -0.7874 -0.4064)
			(stroke
				(width 0.1524)
				(type default)
			)
			(layer "B.SilkS")
		)
		(fp_line
			(start 0.7874 0.4064)
			(end 0.7874 -0.4064)
			(stroke
				(width 0.1524)
				(type default)
			)
			(layer "B.SilkS")
		)
		(fp_line
			(start -0.67945 -0.3048)
			(end -0.67945 0.3048)
			(stroke
				(width 0.1)
				(type default)
			)
			(layer "B.Fab")
		)
		(fp_line
			(start -0.67945 0.3048)
			(end -0.120396 0.3048)
			(stroke
				(width 0.1)
				(type default)
			)
			(layer "B.Fab")
		)
		(fp_line
			(start -0.12065 -0.3048)
			(end -0.67945 -0.3048)
			(stroke
				(width 0.1)
				(type default)
			)
			(layer "B.Fab")
		)
		(fp_line
			(start -0.12065 -0.2794)
			(end -0.12065 -0.3048)
			(stroke
				(width 0.1)
				(type default)
			)
			(layer "B.Fab")
		)
		(fp_line
			(start -0.120396 0.2794)
			(end 0.12065 0.2794)
			(stroke
				(width 0.1)
				(type default)
			)
			(layer "B.Fab")
		)
		(fp_line
			(start -0.120396 0.3048)
			(end -0.120396 0.2794)
			(stroke
				(width 0.1)
				(type default)
			)
			(layer "B.Fab")
		)
		(fp_line
			(start 0.12065 -0.305054)
			(end 0.12065 -0.2794)
			(stroke
				(width 0.1)
				(type default)
			)
			(layer "B.Fab")
		)
		(fp_line
			(start 0.12065 -0.2794)
			(end -0.12065 -0.2794)
			(stroke
				(width 0.1)
				(type default)
			)
			(layer "B.Fab")
		)
		(fp_line
			(start 0.12065 0.2794)
			(end 0.12065 0.3048)
			(stroke
				(width 0.1)
				(type default)
			)
			(layer "B.Fab")
		)
		(fp_line
			(start 0.12065 0.3048)
			(end 0.67945 0.3048)
			(stroke
				(width 0.1)
				(type default)
			)
			(layer "B.Fab")
		)
		(fp_line
			(start 0.67945 -0.305054)
			(end 0.12065 -0.305054)
			(stroke
				(width 0.1)
				(type default)
			)
			(layer "B.Fab")
		)
		(fp_line
			(start 0.67945 0.3048)
			(end 0.67945 -0.305054)
			(stroke
				(width 0.1)
				(type default)
			)
			(layer "B.Fab")
		)
		(pad "1" smd circle
			(at 0.40005 0 180)
			(size 0 0)
			(layers "B.Cu" "B.Mask" "B.Paste")
			(net "P0V9_RETIMER_CPU0_SVID_CLK")
		)
		(pad "2" smd circle
			(at -0.40005 0 180)
			(size 0 0)
			(layers "B.Cu" "B.Mask" "B.Paste")
			(net "GND")
		)
	)
)
